# BASEBOARD_FAB2 (Tioga Pass) — schematic netlist excerpt (pin names and nets, part order shuffled) for the footprints in the layout excerpt that follows; sources: Cadence DE-HDL packaged netlist, KiCad conversion of Wiwynn_Tioga_Pass_MB.brd

R4B13  RES  0 5.0% CHIP  pkg 0603  page 234 : A = VR_PVPP_KLM_BOOT ; B = VR_PVPP_KLM_BOOT_R
R8F21  RES  0.0 5% CHIP  pkg 0402  page 185 : A = P3E_PCH_RX_0_DN ; B = P3E_PCH_M2_SATA6G_RX_R_DN
C4B4  CAP  100.0PF 50V 5% COG  pkg 0402LF  page 234 : A = VR_FB_PVPP_KLM ; B = VR_COMP_PVPP_KLM_3

(kicad_pcb
	(version 20260206)
	(generator "pcbnew")
	(generator_version "10.0")
	(general
		(thickness 1.6)
		(legacy_teardrops no)
	)
	(paper "A4")
	(title_block
		(title "Wiwynn_Tioga_Pass_MB.brd")
		(comment 1 "Tioga Pass / footprints 1740-1742 of 4770")
	)
	(layers
		(0 "F.Cu" signal "TOP")
		(4 "In1.Cu" signal "L2GND")
		(6 "In2.Cu" signal "L3")
		(8 "In3.Cu" signal "L4GND")
		(10 "In4.Cu" signal "L5")
		(12 "In5.Cu" signal "L6GND")
		(14 "In6.Cu" signal "L7VCC")
		(16 "In7.Cu" signal "L8VCC")
		(18 "In8.Cu" signal "L9GND")
		(20 "In9.Cu" signal "L10")
		(22 "In10.Cu" signal "L11GND")
		(24 "In11.Cu" signal "L12")
		(26 "In12.Cu" signal "L13GND")
		(2 "B.Cu" signal "BOTTOM")
		(9 "F.Adhes" user "F.Adhesive")
		(11 "B.Adhes" user "B.Adhesive")
		(13 "F.Paste" user "Package Geometry/Pastemask Top")
		(15 "B.Paste" user "Package Geometry/Pastemask Bottom")
		(5 "F.SilkS" user "Ref Des/Silkscreen Top")
		(7 "B.SilkS" user "Ref Des/Silkscreen Bottom")
		(1 "F.Mask" user "Board Geometry/Soldermask Top")
		(3 "B.Mask" user "Board Geometry/Soldermask Bottom")
		(17 "Dwgs.User" user "User.Drawings")
		(19 "Cmts.User" user "User.Comments")
		(21 "Eco1.User" user "User.Eco1")
		(23 "Eco2.User" user "User.Eco2")
		(25 "Edge.Cuts" user "Board Geometry/Outline")
		(27 "Margin" user)
		(31 "F.CrtYd" user "Package Geometry/Place Bound Top")
		(29 "B.CrtYd" user "Package Geometry/Place Bound Bottom")
		(35 "F.Fab" user "Ref Des/Assembly Top")
		(33 "B.Fab" user "Ref Des/Assembly Bottom")
	)
	(footprint ""
		(layer "F.Cu")
		(at 173.5074 -133.604 -90)
		(property "Reference" "R4B13"
			(at 1.01473 0.656336 180)
			(unlocked yes)
			(layer "F.SilkS")
			(effects
				(font
					(size 0.4064 0.254)
					(thickness 0.1524)
				)
			)
		)
		(property "Value" ""
			(at 0 0 270)
			(layer "F.Fab")
			(effects
				(font
					(size 1.27 1.27)
				)
			)
		)
		(duplicate_pad_numbers_are_jumpers no)
		(fp_poly
			(pts
				(xy -0.4953 -0.2032) (xy 0.4953 -0.2032) (xy 0.4953 1.6002) (xy -0.4953 1.6002)
			)
			(stroke
				(width 0)
				(type default)
			)
			(fill no)
			(layer "F.CrtYd")
		)
		(fp_line
			(start -0.4953 1.6002)
			(end -0.4953 -0.2032)
			(stroke
				(width 0.1)
				(type default)
			)
			(layer "F.Fab")
		)
		(fp_line
			(start 0.4953 1.6002)
			(end -0.4953 1.6002)
			(stroke
				(width 0.1)
				(type default)
			)
			(layer "F.Fab")
		)
		(fp_line
			(start -0.4953 -0.2032)
			(end 0.4953 -0.2032)
			(stroke
				(width 0.1)
				(type default)
			)
			(layer "F.Fab")
		)
		(fp_line
			(start 0.4953 -0.2032)
			(end 0.4953 1.6002)
			(stroke
				(width 0.1)
				(type default)
			)
			(layer "F.Fab")
		)
		(pad "1" smd rect
			(at 0 0 270)
			(size 0.762 0.889)
			(layers "F.Cu" "F.Mask" "F.Paste")
			(net "VR_PVPP_KLM_BOOT")
		)
		(pad "2" smd rect
			(at 0 1.397 270)
			(size 0.762 0.889)
			(layers "F.Cu" "F.Mask" "F.Paste")
			(net "VR_PVPP_KLM_BOOT_R")
		)
		(zone
			(layer "F.Cu")
			(hatch none 0.5)
			(connect_pads
				(clearance 0)
			)
			(min_thickness 0.25)
			(keepout
				(tracks not_allowed)
				(vias allowed)
				(pads allowed)
				(copperpour not_allowed)
				(footprints allowed)
			)
			(placement
				(enabled no)
				(sheetname "")
			)
			(fill
				(thermal_gap 0.5)
				(thermal_bridge_width 0.5)
				(island_removal_mode 0)
			)
			(polygon
				(pts
					(xy 172.5549 -133.985) (xy 172.5549 -133.223) (xy 173.0629 -133.223) (xy 173.0629 -133.985)
				)
			)
		)
		(zone
			(layer "F.Cu")
			(hatch none 0.5)
			(connect_pads
				(clearance 0)
			)
			(min_thickness 0.25)
			(keepout
				(tracks allowed)
				(vias not_allowed)
				(pads allowed)
				(copperpour not_allowed)
				(footprints allowed)
			)
			(placement
				(enabled no)
				(sheetname "")
			)
			(fill
				(thermal_gap 0.5)
				(thermal_bridge_width 0.5)
				(island_removal_mode 0)
			)
			(polygon
				(pts
					(xy 172.5549 -133.223) (xy 173.0629 -133.223) (xy 173.0629 -133.985) (xy 172.5549 -133.985)
				)
			)
		)
	)
	(footprint ""
		(layer "F.Cu")
		(at 379.2982 -30.629352 -90)
		(property "Reference" "R8F21"
			(at 0 0 270)
			(layer "F.SilkS")
			(hide yes)
			(effects
				(font
					(size 1.27 1.27)
				)
			)
		)
		(property "Value" ""
			(at 0 0 270)
			(layer "F.Fab")
			(effects
				(font
					(size 1.27 1.27)
				)
			)
		)
		(duplicate_pad_numbers_are_jumpers no)
		(fp_poly
			(pts
				(xy -0.2794 -0.1016) (xy 0.2794 -0.1016) (xy 0.2794 0.9906) (xy -0.2794 0.9906)
			)
			(stroke
				(width 0)
				(type default)
			)
			(fill no)
			(layer "F.CrtYd")
		)
		(fp_line
			(start -0.2794 0.9906)
			(end 0.2794 0.9906)
			(stroke
				(width 0.1)
				(type default)
			)
			(layer "F.Fab")
		)
		(fp_line
			(start 0.2794 0.9906)
			(end 0.2794 -0.1016)
			(stroke
				(width 0.1)
				(type default)
			)
			(layer "F.Fab")
		)
		(fp_line
			(start -0.2794 -0.1016)
			(end -0.2794 0.9906)
			(stroke
				(width 0.1)
				(type default)
			)
			(layer "F.Fab")
		)
		(fp_line
			(start 0.2794 -0.1016)
			(end -0.2794 -0.1016)
			(stroke
				(width 0.1)
				(type default)
			)
			(layer "F.Fab")
		)
		(pad "1" smd rect
			(at 0 0 270)
			(size 0.508 0.508)
			(layers "F.Cu" "F.Mask" "F.Paste")
			(net "P3E_PCH_RX_0_DN")
		)
		(pad "2" smd rect
			(at 0 0.889 270)
			(size 0.508 0.508)
			(layers "F.Cu" "F.Mask" "F.Paste")
			(net "P3E_PCH_M2_SATA6G_RX_R_DN")
		)
		(zone
			(layer "F.Cu")
			(hatch none 0.5)
			(connect_pads
				(clearance 0)
			)
			(min_thickness 0.25)
			(keepout
				(tracks not_allowed)
				(vias allowed)
				(pads allowed)
				(copperpour not_allowed)
				(footprints allowed)
			)
			(placement
				(enabled no)
				(sheetname "")
			)
			(fill
				(thermal_gap 0.5)
				(thermal_bridge_width 0.5)
				(island_removal_mode 0)
			)
			(polygon
				(pts
					(xy 378.6632 -30.883352) (xy 378.6632 -30.375352) (xy 379.0442 -30.375352) (xy 379.0442 -30.883352)
				)
			)
		)
		(zone
			(layer "F.Cu")
			(hatch none 0.5)
			(connect_pads
				(clearance 0)
			)
			(min_thickness 0.25)
			(keepout
				(tracks allowed)
				(vias not_allowed)
				(pads allowed)
				(copperpour not_allowed)
				(footprints allowed)
			)
			(placement
				(enabled no)
				(sheetname "")
			)
			(fill
				(thermal_gap 0.5)
				(thermal_bridge_width 0.5)
				(island_removal_mode 0)
			)
			(polygon
				(pts
					(xy 379.0442 -30.883352) (xy 379.0442 -30.375352) (xy 378.6632 -30.375352) (xy 378.6632 -30.883352)
				)
			)
		)
	)
	(footprint ""
		(layer "F.Cu")
		(at 176.0855 -132.334 90)
		(property "Reference" "C4B4"
			(at 0 0 90)
			(layer "F.SilkS")
			(hide yes)
			(effects
				(font
					(size 1.27 1.27)
				)
			)
		)
		(property "Value" ""
			(at 0 0 90)
			(layer "F.Fab")
			(effects
				(font
					(size 1.27 1.27)
				)
			)
		)
		(duplicate_pad_numbers_are_jumpers no)
		(fp_poly
			(pts
				(xy 0.3048 -0.1016) (xy 0.3048 0.9906) (xy -0.3048 0.9906) (xy -0.3048 -0.1016)
			)
			(stroke
				(width 0)
				(type default)
			)
			(fill no)
			(layer "F.CrtYd")
		)
		(fp_line
			(start 0.3048 -0.1016)
			(end -0.3048 -0.1016)
			(stroke
				(width 0.1)
				(type default)
			)
			(layer "F.Fab")
		)
		(fp_line
			(start -0.3048 -0.1016)
			(end -0.3048 0.9906)
			(stroke
				(width 0.1)
				(type default)
			)
			(layer "F.Fab")
		)
		(fp_line
			(start 0.3048 0.9906)
			(end 0.3048 -0.1016)
			(stroke
				(width 0.1)
				(type default)
			)
			(layer "F.Fab")
		)
		(fp_line
			(start -0.3048 0.9906)
			(end 0.3048 0.9906)
			(stroke
				(width 0.1)
				(type default)
			)
			(layer "F.Fab")
		)
		(pad "1" smd rect
			(at 0 0 90)
			(size 0.508 0.508)
			(layers "F.Cu" "F.Mask" "F.Paste")
			(net "VR_FB_PVPP_KLM")
		)
		(pad "2" smd rect
			(at 0 0.889 90)
			(size 0.508 0.508)
			(layers "F.Cu" "F.Mask" "F.Paste")
			(net "VR_COMP_PVPP_KLM_3")
		)
		(zone
			(layer "F.Cu")
			(hatch none 0.5)
			(connect_pads
				(clearance 0)
			)
			(min_thickness 0.25)
			(keepout
				(tracks allowed)
				(vias not_allowed)
				(pads allowed)
				(copperpour not_allowed)
				(footprints allowed)
			)
			(placement
				(enabled no)
				(sheetname "")
			)
			(fill
				(thermal_gap 0.5)
				(thermal_bridge_width 0.5)
				(island_removal_mode 0)
			)
			(polygon
				(pts
					(xy 176.3395 -132.08) (xy 176.3395 -132.588) (xy 176.7205 -132.588) (xy 176.7205 -132.08)
				)
			)
		)
		(zone
			(layer "F.Cu")
			(hatch none 0.5)
			(connect_pads
				(clearance 0)
			)
			(min_thickness 0.25)
			(keepout
				(tracks not_allowed)
				(vias allowed)
				(pads allowed)
				(copperpour not_allowed)
				(footprints allowed)
			)
			(placement
				(enabled no)
				(sheetname "")
			)
			(fill
				(thermal_gap 0.5)
				(thermal_bridge_width 0.5)
				(island_removal_mode 0)
			)
			(polygon
				(pts
					(xy 176.7205 -132.08) (xy 176.7205 -132.588) (xy 176.3395 -132.588) (xy 176.3395 -132.08)
				)
			)
		)
	)
)
